FILE_TYPE = CONNECTIVITY;
{Allegro Design Entry HDL 17.2-2016 S081 (4005846) 1/11/2022}
"PAGE_NUMBER" = 134;
0"NC";
1"P3V3_AUX\g";
2"P1V05_PCH_AUX\g";
3"PVNN_TERM_CPU0\g";
4"PVNN_TERM_CPU0\g";
5"P3V3_AUX\g";
6"GND\g";
7"GND\g";
8"GND\g";
9"GND\g";
10"GND\g";
11"DBP_CPU_HOOK9_MBP3_GTL_QS_N"CDS_PHYS_NET_NAME"TRC_PCH_PTI1_CLK";
12"DBP_CPU_HOOK8_MBP2_GTL_QS_N"CDS_PHYS_NET_NAME"TRC_PCH_PTI1_CLK";
13"JTAG_DBP_TDI_PCH"CDS_PHYS_NET_NAME"TRC_PCH_PTI1_CLK";
14"JTAG_DBP_TMS_PCH"CDS_PHYS_NET_NAME"TRC_PCH_PTI1_CLK";
15"JTAG_DBP_TDO_PCH"CDS_PHYS_NET_NAME"TRC_PCH_PTI1_CLK";
16"H_CPU_PRDY_QS_GTL_N"CDS_PHYS_NET_NAME"TRC_PCH_PTI1_CLK";
17"H_CPU_PREQ_QS_GTL_N"CDS_PHYS_NET_NAME"TRC_PCH_PTI1_CLK";
18"H_DBP_PREQ_N_PCH"CDS_PHYS_NET_NAME"TRC_PCH_PTI1_CLK";
19"H_DBP_PRDY_N_PCH"CDS_PHYS_NET_NAME"TRC_PCH_PTI1_CLK";
20"JTAG_DBP_CPU_QS_GTL_TMS"CDS_PHYS_NET_NAME"TRC_PCH_PTI1_CLK";
21"JTAG_DBP_TDI"CDS_PHYS_NET_NAME"TRC_PCH_PTI1_CLK";
22"JTAG_DBP_TDO"CDS_PHYS_NET_NAME"TRC_PCH_PTI1_CLK";
23"JTAG_DBP_TMS"CDS_PHYS_NET_NAME"TRC_PCH_PTI1_CLK";
24"PD_74CB_A9"CDS_PHYS_NET_NAME"TRC_PCH_PTI1_CLK";
25"JTAG_DBP_PRDY_N"CDS_PHYS_NET_NAME"TRC_PCH_PTI1_CLK";
26"JTAG_DBP_PREQ_N"CDS_PHYS_NET_NAME"TRC_PCH_PTI1_CLK";
27"JTAG_QS_MUX_GTL_TDI"CDS_PHYS_NET_NAME"TRC_PCH_PTI1_CLK";
28"TP_74CB_B8"CDS_PHYS_NET_NAME"TRC_PCH_PTI1_CLK";
29"JTAG_MUX_QS_GTL_TDO"CDS_PHYS_NET_NAME"TRC_PCH_PTI1_CLK";
30"PWRGD_PVNN_MAIN_CPU0"CDS_PHYS_NET_NAME"TRC_PCH_PTI1_CLK";
31"JTAG_DBP_TMS"CDS_PHYS_NET_NAME"TRC_PCH_PTI1_CLK";
32"PWRGD_PVNN_MAIN_CPU0"CDS_PHYS_NET_NAME"TRC_PCH_PTI1_CLK";
33"JTAG_DBP_PREQ_N"CDS_PHYS_NET_NAME"TRC_PCH_PTI1_CLK";
34"JTAG_DBP_PRDY_N"CDS_PHYS_NET_NAME"TRC_PCH_PTI1_CLK";
35"JTAG_DBP_CPU_HOOK8_MBP2_GTL_N"CDS_PHYS_NET_NAME"TRC_PCH_PTI1_CLK";
36"JTAG_DBP_CPU_HOOK9_MBP3_GTL_N"CDS_PHYS_NET_NAME"TRC_PCH_PTI1_CLK";
37"JTAG_DBP_TDI"CDS_PHYS_NET_NAME"TRC_PCH_PTI1_CLK";
38"JTAG_DBP_TDO"CDS_PHYS_NET_NAME"TRC_PCH_PTI1_CLK";
%"Q_RES"
"1","(-575,-150)","0","pure_quanta","I126";
;
PART_NUMBER"CS01002FB07"
MATERIAL"CHIP"
PACK_TYPE"0402LF"
TOLERANCE"1%"
WATTAGE"1/16W"
VALUE"10"
$LOCATION"R754"
CDS_LIB"pure_quanta"
CDS_LOCATION"R754"
$SEC"1"
CDS_SEC"1";
"B"
$PN"2"14;
"A"
$PN"1"23;
%"Q_RES"
"1","(-575,0)","0","pure_quanta","I127";
;
PART_NUMBER"CS01002FB07"
VALUE"10"
MATERIAL"CHIP"
WATTAGE"1/16W"
TOLERANCE"1%"
PACK_TYPE"0402LF"
$LOCATION"R752"
CDS_LIB"pure_quanta"
CDS_LOCATION"R752"
$SEC"1"
CDS_SEC"1";
"B"
$PN"2"15;
"A"
$PN"1"22;
%"Q_RES"
"1","(-575,-75)","0","pure_quanta","I128";
;
PART_NUMBER"CS01002FB07"
PACK_TYPE"0402LF"
VALUE"10"
MATERIAL"CHIP"
WATTAGE"1/16W"
TOLERANCE"1%"
$LOCATION"R753"
CDS_LIB"pure_quanta"
CDS_LOCATION"R753"
$SEC"1"
CDS_SEC"1";
"B"
$PN"2"13;
"A"
$PN"1"21;
%"74CBTLV3126PW"
"1","(-350,1700)","0","pure_quanta","I129";
;
PART_NUMBER"AL003126K08"
PART_TYPE"SMLF"
MATERIAL"IC"
VALUE"74CBTLV3126PW"
$LOCATION"U18"
CDS_LMAN_SYM_OUTLINE"-250,350,250,-350"
NEEDS_NO_SIZE"TRUE"
CDS_LIB"pure_quanta"
SEC_TYPE""
CDS_LOCATION"U18"
SEC"1";
"VCC"
$PN"14"5;
"4OE"
$PN"13"32;
"4A"
$PN"12"33;
"4B"
$PN"11"17;
"3OE"
$PN"10"32;
"3A"
$PN"9"34;
"GND"
$PN"7"8;
"1A"
$PN"2"36;
"2B"
$PN"6"12;
"1B"
$PN"3"11;
"2OE"
$PN"4"32;
"1OE"
$PN"1"32;
"3B"
$PN"8"16;
"2A"
$PN"5"35;
%"UNIVERSAL_POWER"
"1","(125,2450)","0","logical_power","I134";
;
HDL_POWER"P3V3_AUX"
CDS_LIB"logical_power";
"A"5;
%"Q_CAP"
"1","(275,2200)","0","pure_quanta","I135";
;
PART_NUMBER"CH5104KEB02"
PACK_TYPE"C0402"
MATERIAL"X6S"
TOLERANCE"10%"
VOLTAGE"25V"
VALUE"1UF"
$LOCATION"C546"
CDS_LIB"pure_quanta"
CDS_LOCATION"C546"
$SEC"1"
CDS_SEC"1";
"B"
$PN"2"10;
"A"
$PN"1"5;
%"UNIVERSAL_GND"
"1","(275,2000)","0","logical_power","I136";
;
CDS_LIB"logical_power"
HDL_POWER"GND";
"A"10;
%"Q_RES"
"1","(-575,-225)","0","pure_quanta","I147";
;
PART_NUMBER"CS01002FB07"
WATTAGE"1/16W"
PACK_TYPE"0402LF"
MATERIAL"CHIP"
TOLERANCE"1%"
VALUE"10"
$LOCATION"R755"
CDS_LIB"pure_quanta"
CDS_LOCATION"R755"
$SEC"1"
CDS_SEC"1";
"B"
$PN"2"18;
"A"
$PN"1"26;
%"Q_RES"
"1","(-575,-300)","0","pure_quanta","I148";
;
PART_NUMBER"CS01002FB07"
PACK_TYPE"0402LF"
MATERIAL"CHIP"
WATTAGE"1/16W"
TOLERANCE"1%"
VALUE"10"
$LOCATION"R756"
CDS_LIB"pure_quanta"
CDS_LOCATION"R756"
$SEC"1"
CDS_SEC"1";
"B"
$PN"2"19;
"A"
$PN"1"25;
%"UNIVERSAL_GND"
"1","(125,3150)","0","logical_power","I164";
;
CDS_LIB"logical_power"
HDL_POWER"GND";
"A"9;
%"UNIVERSAL_GND"
"1","(125,1250)","0","logical_power","I165";
;
CDS_LIB"logical_power"
HDL_POWER"GND";
"A"8;
%"Q_RES"
"2","(1050,4075)","0","pure_quanta","I166";
;
PART_NUMBER"CS11202FB02"
TOLERANCE"1%"
VALUE"120"
MATERIAL"CHIP"
WATTAGE"1/16W"
PACK_TYPE"0402LF"
$LOCATION"R757"
CDS_LIB"pure_quanta"
CDS_LOCATION"R757"
$SEC"1"
CDS_SEC"1";
"A"
$PN"1"4;
"B"
$PN"2"20;
%"UNIVERSAL_POWER"
"1","(1050,4325)","0","logical_power","I167";
;
HDL_POWER"PVNN_TERM_CPU0"
CDS_LIB"logical_power";
"A"4;
%"Q_RES"
"2","(1125,2225)","0","pure_quanta","I168";
;
PART_NUMBER"CS11502FB07"
VALUE"150"
TOLERANCE"1%"
PACK_TYPE"0402LF"
WATTAGE"1/16W"
MATERIAL"CHIP"
$LOCATION"R758"
CDS_LIB"pure_quanta"
CDS_LOCATION"R758"
$SEC"1"
CDS_SEC"1";
"A"
$PN"1"3;
"B"
$PN"2"17;
%"Q_RES"
"2","(1550,2225)","0","pure_quanta","I169";
;
PART_NUMBER"CS11502FB07"
PACK_TYPE"0402LF"
MATERIAL"CHIP"
WATTAGE"1/16W"
TOLERANCE"1%"
VALUE"150"
$LOCATION"R759"
CDS_LIB"pure_quanta"
CDS_LOCATION"R759"
$SEC"1"
CDS_SEC"1";
"A"
$PN"1"3;
"B"
$PN"2"16;
%"UNIVERSAL_POWER"
"1","(1125,2575)","0","logical_power","I172";
;
HDL_POWER"PVNN_TERM_CPU0"
CDS_LIB"logical_power";
"A"3;
%"Q_RES"
"2","(2000,2200)","0","pure_quanta","I174";
;
PART_NUMBER"CS14992FB06"
WATTAGE"1/16W"
PACK_TYPE"0402LF"
MATERIAL"CHIP"
VALUE"499"
TOLERANCE"1%"
$LOCATION"R760"
CDS_LIB"pure_quanta"
CDS_LOCATION"R760"
$SEC"1"
CDS_SEC"1";
"A"
$PN"1"3;
"B"
$PN"2"12;
%"Q_RES"
"2","(2350,2200)","0","pure_quanta","I175";
;
PART_NUMBER"CS14992FB06"
WATTAGE"1/16W"
PACK_TYPE"0402LF"
MATERIAL"CHIP"
VALUE"499"
TOLERANCE"1%"
$LOCATION"R761"
CDS_LIB"pure_quanta"
CDS_LOCATION"R761"
$SEC"1"
CDS_SEC"1";
"A"
$PN"1"3;
"B"
$PN"2"11;
%"Q_RES"
"2","(825,250)","0","pure_quanta","I176";
;
PART_NUMBER"CS11502FB07"
MATERIAL"CHIP"
PACK_TYPE"0402LF"
TOLERANCE"1%"
VALUE"150"
WATTAGE"1/16W"
$LOCATION"R747"
CDS_LIB"pure_quanta"
CDS_LOCATION"R747"
$SEC"1"
CDS_SEC"1";
"A"
$PN"1"2;
"B"
$PN"2"15;
%"Q_RES"
"2","(2225,250)","0","pure_quanta","I177";
;
PART_NUMBER"CS11502FB07"
TOLERANCE"1%"
MATERIAL"CHIP"
PACK_TYPE"0402LF"
WATTAGE"1/16W"
VALUE"150"
$LOCATION"R751"
CDS_LIB"pure_quanta"
CDS_LOCATION"R751"
$SEC"1"
CDS_SEC"1";
"A"
$PN"1"2;
"B"
$PN"2"19;
%"Q_RES"
"2","(1875,250)","0","pure_quanta","I178";
;
PART_NUMBER"CS11502FB07"
PACK_TYPE"0402LF"
MATERIAL"CHIP"
VALUE"150"
TOLERANCE"1%"
WATTAGE"1/16W"
$LOCATION"R750"
CDS_LIB"pure_quanta"
CDS_LOCATION"R750"
$SEC"1"
CDS_SEC"1";
"A"
$PN"1"2;
"B"
$PN"2"18;
%"Q_RES"
"2","(1525,250)","0","pure_quanta","I179";
;
PART_NUMBER"CS07502FB04"
VALUE"75"
TOLERANCE"1%"
MATERIAL"CHIP"
PACK_TYPE"0402LF"
WATTAGE"1/16W"
$LOCATION"R749"
CDS_LIB"pure_quanta"
CDS_LOCATION"R749"
$SEC"1"
CDS_SEC"1";
"A"
$PN"1"2;
"B"
$PN"2"14;
%"Q_RES"
"2","(1175,250)","0","pure_quanta","I180";
;
PART_NUMBER"CS07502FB04"
MATERIAL"CHIP"
TOLERANCE"1%"
PACK_TYPE"0402LF"
WATTAGE"1/16W"
VALUE"75"
$LOCATION"R748"
CDS_LIB"pure_quanta"
CDS_LOCATION"R748"
$SEC"1"
CDS_SEC"1";
"A"
$PN"1"2;
"B"
$PN"2"13;
%"UNIVERSAL_POWER"
"1","(825,550)","0","logical_power","I181";
;
HDL_POWER"P1V05_PCH_AUX"
CDS_LIB"logical_power";
"A"2;
%"74CBTLV3126PW"
"1","(-350,3600)","0","pure_quanta","I80";
;
PART_NUMBER"AL003126K08"
PART_TYPE"SMLF"
MATERIAL"IC"
VALUE"74CBTLV3126PW"
$LOCATION"U17"
CDS_LMAN_SYM_OUTLINE"-250,350,250,-350"
NEEDS_NO_SIZE"TRUE"
CDS_LIB"pure_quanta"
SEC_TYPE""
CDS_LOCATION"U17"
SEC"1";
"VCC"
$PN"14"1;
"4OE"
$PN"13"30;
"4A"
$PN"12"38;
"4B"
$PN"11"29;
"3OE"
$PN"10"30;
"3A"
$PN"9"24;
"GND"
$PN"7"9;
"1A"
$PN"2"31;
"2B"
$PN"6"27;
"1B"
$PN"3"20;
"2OE"
$PN"4"30;
"1OE"
$PN"1"30;
"3B"
$PN"8"28;
"2A"
$PN"5"37;
%"UNIVERSAL_POWER"
"1","(125,4350)","0","logical_power","I81";
;
HDL_POWER"P3V3_AUX"
CDS_LIB"logical_power";
"A"1;
%"Q_RES"
"2","(-1900,3025)","2","pure_quanta","I90";
;
PART_NUMBER"CS00002JB13"
VALUE"0"
TOLERANCE"5%"
PACK_TYPE"0402LF"
WATTAGE"1/16W"
MATERIAL"CHIP"
$LOCATION"R746"
CDS_LIB"pure_quanta"
CDS_LOCATION"R746"
$SEC"1"
CDS_SEC"1";
"A"
$PN"1"24;
"B"
$PN"2"7;
%"UNIVERSAL_GND"
"1","(-1900,2775)","0","logical_power","I91";
;
CDS_LIB"logical_power"
HDL_POWER"GND";
"A"7;
%"UNIVERSAL_GND"
"1","(275,3900)","0","logical_power","I92";
;
CDS_LIB"logical_power"
HDL_POWER"GND";
"A"6;
%"Q_CAP"
"1","(275,4100)","0","pure_quanta","I93";
;
PART_NUMBER"CH5104KEB02"
PACK_TYPE"C0402"
MATERIAL"X6S"
TOLERANCE"10%"
VOLTAGE"25V"
VALUE"1UF"
$LOCATION"C545"
CDS_LIB"pure_quanta"
CDS_LOCATION"C545"
$SEC"1"
CDS_SEC"1";
"B"
$PN"2"6;
"A"
$PN"1"1;
END.
